(kicad_pcb
	(version 20260206)
	(generator "pcbnew")
	(generator_version "10.0")
	(general
		(thickness 1.6)
		(legacy_teardrops no)
	)
	(paper "A4")
	(title_block
		(title "03242023_DA0F0TMBIJ0_F0T_Motherboard_J_brd_V01_OCP.brd")
		(comment 1 "Grand Teton / footprints 1278-1283 of 6105")
	)
	(layers
		(0 "F.Cu" signal "TOP")
		(4 "In1.Cu" signal "GND")
		(6 "In2.Cu" signal "IN1")
		(8 "In3.Cu" signal "GND1")
		(10 "In4.Cu" signal "IN2")
		(12 "In5.Cu" signal "GND2")
		(14 "In6.Cu" signal "IN3")
		(16 "In7.Cu" signal "GND3")
		(18 "In8.Cu" signal "VCC")
		(20 "In9.Cu" signal "VCC1")
		(22 "In10.Cu" signal "GND4")
		(24 "In11.Cu" signal "IN4")
		(26 "In12.Cu" signal "GND5")
		(28 "In13.Cu" signal "IN5")
		(30 "In14.Cu" signal "GND6")
		(32 "In15.Cu" signal "IN6")
		(34 "In16.Cu" signal "GND7")
		(2 "B.Cu" signal "BOTTOM")
		(9 "F.Adhes" user "F.Adhesive")
		(11 "B.Adhes" user "B.Adhesive")
		(13 "F.Paste" user "Package Geometry/Pastemask Top")
		(15 "B.Paste" user "Package Geometry/Pastemask Bottom")
		(5 "F.SilkS" user "Ref Des/Silkscreen Top")
		(7 "B.SilkS" user "Ref Des/Silkscreen Bottom")
		(1 "F.Mask" user "Board Geometry/Soldermask Top")
		(3 "B.Mask" user "Board Geometry/Soldermask Bottom")
		(17 "Dwgs.User" user "User.Drawings")
		(19 "Cmts.User" user "User.Comments")
		(21 "Eco1.User" user "User.Eco1")
		(23 "Eco2.User" user "User.Eco2")
		(25 "Edge.Cuts" user "Board Geometry/Outline")
		(27 "Margin" user)
		(31 "F.CrtYd" user "Package Geometry/Place Bound Top")
		(29 "B.CrtYd" user "Package Geometry/Place Bound Bottom")
		(35 "F.Fab" user "Ref Des/Assembly Top")
		(33 "B.Fab" user "Ref Des/Assembly Bottom")
	)
	(footprint ""
		(layer "F.Cu")
		(at 257.87985 -39.484046 90)
		(property "Reference" "PR4528"
			(at 0 0 90)
			(layer "F.SilkS")
			(hide yes)
			(effects
				(font
					(size 1.27 1.27)
				)
			)
		)
		(property "Value" ""
			(at 0 0 90)
			(layer "F.Fab")
			(effects
				(font
					(size 1.27 1.27)
				)
			)
		)
		(duplicate_pad_numbers_are_jumpers no)
		(fp_line
			(start 0.7874 -0.4064)
			(end 0.7874 0.4064)
			(stroke
				(width 0.1524)
				(type default)
			)
			(layer "F.SilkS")
		)
		(fp_line
			(start -0.7874 -0.4064)
			(end 0.7874 -0.4064)
			(stroke
				(width 0.1524)
				(type default)
			)
			(layer "F.SilkS")
		)
		(fp_line
			(start 0.7874 0.4064)
			(end -0.7874 0.4064)
			(stroke
				(width 0.1524)
				(type default)
			)
			(layer "F.SilkS")
		)
		(fp_line
			(start -0.7874 0.4064)
			(end -0.7874 -0.4064)
			(stroke
				(width 0.1524)
				(type default)
			)
			(layer "F.SilkS")
		)
		(fp_line
			(start -0.12065 -0.305054)
			(end -0.12065 -0.2794)
			(stroke
				(width 0.1)
				(type default)
			)
			(layer "F.Fab")
		)
		(fp_line
			(start -0.67945 -0.305054)
			(end -0.12065 -0.305054)
			(stroke
				(width 0.1)
				(type default)
			)
			(layer "F.Fab")
		)
		(fp_line
			(start 0.67945 -0.3048)
			(end 0.67945 0.3048)
			(stroke
				(width 0.1)
				(type default)
			)
			(layer "F.Fab")
		)
		(fp_line
			(start 0.12065 -0.3048)
			(end 0.67945 -0.3048)
			(stroke
				(width 0.1)
				(type default)
			)
			(layer "F.Fab")
		)
		(fp_line
			(start 0.12065 -0.2794)
			(end 0.12065 -0.3048)
			(stroke
				(width 0.1)
				(type default)
			)
			(layer "F.Fab")
		)
		(fp_line
			(start -0.12065 -0.2794)
			(end 0.12065 -0.2794)
			(stroke
				(width 0.1)
				(type default)
			)
			(layer "F.Fab")
		)
		(fp_line
			(start 0.120396 0.2794)
			(end -0.12065 0.2794)
			(stroke
				(width 0.1)
				(type default)
			)
			(layer "F.Fab")
		)
		(fp_line
			(start -0.12065 0.2794)
			(end -0.12065 0.3048)
			(stroke
				(width 0.1)
				(type default)
			)
			(layer "F.Fab")
		)
		(fp_line
			(start 0.67945 0.3048)
			(end 0.120396 0.3048)
			(stroke
				(width 0.1)
				(type default)
			)
			(layer "F.Fab")
		)
		(fp_line
			(start 0.120396 0.3048)
			(end 0.120396 0.2794)
			(stroke
				(width 0.1)
				(type default)
			)
			(layer "F.Fab")
		)
		(fp_line
			(start -0.12065 0.3048)
			(end -0.67945 0.3048)
			(stroke
				(width 0.1)
				(type default)
			)
			(layer "F.Fab")
		)
		(fp_line
			(start -0.67945 0.3048)
			(end -0.67945 -0.305054)
			(stroke
				(width 0.1)
				(type default)
			)
			(layer "F.Fab")
		)
		(pad "1" smd circle
			(at -0.40005 0 90)
			(size 0 0)
			(layers "F.Cu" "F.Mask" "F.Paste")
			(net "P12V_E1S_0")
		)
		(pad "2" smd circle
			(at 0.40005 0 90)
			(size 0 0)
			(layers "F.Cu" "F.Mask" "F.Paste")
			(net "P12V_E1S_GATE_0")
		)
	)
	(footprint ""
		(layer "F.Cu")
		(at 365.390938 -417.15309 90)
		(property "Reference" "R4209"
			(at 0 0 90)
			(layer "F.SilkS")
			(hide yes)
			(effects
				(font
					(size 1.27 1.27)
				)
			)
		)
		(property "Value" ""
			(at 0 0 90)
			(layer "F.Fab")
			(effects
				(font
					(size 1.27 1.27)
				)
			)
		)
		(duplicate_pad_numbers_are_jumpers no)
		(fp_line
			(start 0.7874 -0.4064)
			(end 0.7874 0.4064)
			(stroke
				(width 0.1524)
				(type default)
			)
			(layer "F.SilkS")
		)
		(fp_line
			(start -0.7874 -0.4064)
			(end 0.7874 -0.4064)
			(stroke
				(width 0.1524)
				(type default)
			)
			(layer "F.SilkS")
		)
		(fp_line
			(start 0.7874 0.4064)
			(end -0.7874 0.4064)
			(stroke
				(width 0.1524)
				(type default)
			)
			(layer "F.SilkS")
		)
		(fp_line
			(start -0.7874 0.4064)
			(end -0.7874 -0.4064)
			(stroke
				(width 0.1524)
				(type default)
			)
			(layer "F.SilkS")
		)
		(fp_line
			(start -0.12065 -0.305054)
			(end -0.12065 -0.2794)
			(stroke
				(width 0.1)
				(type default)
			)
			(layer "F.Fab")
		)
		(fp_line
			(start -0.67945 -0.305054)
			(end -0.12065 -0.305054)
			(stroke
				(width 0.1)
				(type default)
			)
			(layer "F.Fab")
		)
		(fp_line
			(start 0.67945 -0.3048)
			(end 0.67945 0.3048)
			(stroke
				(width 0.1)
				(type default)
			)
			(layer "F.Fab")
		)
		(fp_line
			(start 0.12065 -0.3048)
			(end 0.67945 -0.3048)
			(stroke
				(width 0.1)
				(type default)
			)
			(layer "F.Fab")
		)
		(fp_line
			(start 0.12065 -0.2794)
			(end 0.12065 -0.3048)
			(stroke
				(width 0.1)
				(type default)
			)
			(layer "F.Fab")
		)
		(fp_line
			(start -0.12065 -0.2794)
			(end 0.12065 -0.2794)
			(stroke
				(width 0.1)
				(type default)
			)
			(layer "F.Fab")
		)
		(fp_line
			(start 0.120396 0.2794)
			(end -0.12065 0.2794)
			(stroke
				(width 0.1)
				(type default)
			)
			(layer "F.Fab")
		)
		(fp_line
			(start -0.12065 0.2794)
			(end -0.12065 0.3048)
			(stroke
				(width 0.1)
				(type default)
			)
			(layer "F.Fab")
		)
		(fp_line
			(start 0.67945 0.3048)
			(end 0.120396 0.3048)
			(stroke
				(width 0.1)
				(type default)
			)
			(layer "F.Fab")
		)
		(fp_line
			(start 0.120396 0.3048)
			(end 0.120396 0.2794)
			(stroke
				(width 0.1)
				(type default)
			)
			(layer "F.Fab")
		)
		(fp_line
			(start -0.12065 0.3048)
			(end -0.67945 0.3048)
			(stroke
				(width 0.1)
				(type default)
			)
			(layer "F.Fab")
		)
		(fp_line
			(start -0.67945 0.3048)
			(end -0.67945 -0.305054)
			(stroke
				(width 0.1)
				(type default)
			)
			(layer "F.Fab")
		)
		(pad "1" smd circle
			(at -0.40005 0 90)
			(size 0 0)
			(layers "F.Cu" "F.Mask" "F.Paste")
			(net "P3V3_AUX")
		)
		(pad "2" smd circle
			(at 0.40005 0 90)
			(size 0 0)
			(layers "F.Cu" "F.Mask" "F.Paste")
			(net "FM_THERMAL_ALERT_N")
		)
	)
	(footprint ""
		(layer "F.Cu")
		(at 182.471822 -358.15778 90)
		(property "Reference" "PR1802"
			(at 0 0 90)
			(layer "F.SilkS")
			(hide yes)
			(effects
				(font
					(size 1.27 1.27)
				)
			)
		)
		(property "Value" ""
			(at 0 0 90)
			(layer "F.Fab")
			(effects
				(font
					(size 1.27 1.27)
				)
			)
		)
		(duplicate_pad_numbers_are_jumpers no)
		(fp_line
			(start 0.7874 -0.4064)
			(end 0.7874 0.4064)
			(stroke
				(width 0.1524)
				(type default)
			)
			(layer "F.SilkS")
		)
		(fp_line
			(start -0.7874 -0.4064)
			(end 0.7874 -0.4064)
			(stroke
				(width 0.1524)
				(type default)
			)
			(layer "F.SilkS")
		)
		(fp_line
			(start 0.7874 0.4064)
			(end -0.7874 0.4064)
			(stroke
				(width 0.1524)
				(type default)
			)
			(layer "F.SilkS")
		)
		(fp_line
			(start -0.7874 0.4064)
			(end -0.7874 -0.4064)
			(stroke
				(width 0.1524)
				(type default)
			)
			(layer "F.SilkS")
		)
		(fp_line
			(start -0.12065 -0.305054)
			(end -0.12065 -0.2794)
			(stroke
				(width 0.1)
				(type default)
			)
			(layer "F.Fab")
		)
		(fp_line
			(start -0.67945 -0.305054)
			(end -0.12065 -0.305054)
			(stroke
				(width 0.1)
				(type default)
			)
			(layer "F.Fab")
		)
		(fp_line
			(start 0.67945 -0.3048)
			(end 0.67945 0.3048)
			(stroke
				(width 0.1)
				(type default)
			)
			(layer "F.Fab")
		)
		(fp_line
			(start 0.12065 -0.3048)
			(end 0.67945 -0.3048)
			(stroke
				(width 0.1)
				(type default)
			)
			(layer "F.Fab")
		)
		(fp_line
			(start 0.12065 -0.2794)
			(end 0.12065 -0.3048)
			(stroke
				(width 0.1)
				(type default)
			)
			(layer "F.Fab")
		)
		(fp_line
			(start -0.12065 -0.2794)
			(end 0.12065 -0.2794)
			(stroke
				(width 0.1)
				(type default)
			)
			(layer "F.Fab")
		)
		(fp_line
			(start 0.120396 0.2794)
			(end -0.12065 0.2794)
			(stroke
				(width 0.1)
				(type default)
			)
			(layer "F.Fab")
		)
		(fp_line
			(start -0.12065 0.2794)
			(end -0.12065 0.3048)
			(stroke
				(width 0.1)
				(type default)
			)
			(layer "F.Fab")
		)
		(fp_line
			(start 0.67945 0.3048)
			(end 0.120396 0.3048)
			(stroke
				(width 0.1)
				(type default)
			)
			(layer "F.Fab")
		)
		(fp_line
			(start 0.120396 0.3048)
			(end 0.120396 0.2794)
			(stroke
				(width 0.1)
				(type default)
			)
			(layer "F.Fab")
		)
		(fp_line
			(start -0.12065 0.3048)
			(end -0.67945 0.3048)
			(stroke
				(width 0.1)
				(type default)
			)
			(layer "F.Fab")
		)
		(fp_line
			(start -0.67945 0.3048)
			(end -0.67945 -0.305054)
			(stroke
				(width 0.1)
				(type default)
			)
			(layer "F.Fab")
		)
		(pad "1" smd circle
			(at -0.40005 0 90)
			(size 0 0)
			(layers "F.Cu" "F.Mask" "F.Paste")
			(net "SW_PVCCFA_EHV_FIVRA_CPU1_BOOT3")
		)
		(pad "2" smd circle
			(at 0.40005 0 90)
			(size 0 0)
			(layers "F.Cu" "F.Mask" "F.Paste")
			(net "SW_PVCCFA_EHV_FIVRA_CPU1_BOOT3_")
		)
	)
	(footprint ""
		(layer "F.Cu")
		(at 417.946332 -366.691164 -90)
		(property "Reference" "PC606"
			(at 0 0 270)
			(layer "F.SilkS")
			(hide yes)
			(effects
				(font
					(size 1.27 1.27)
				)
			)
		)
		(property "Value" ""
			(at 0 0 270)
			(layer "F.Fab")
			(effects
				(font
					(size 1.27 1.27)
				)
			)
		)
		(duplicate_pad_numbers_are_jumpers no)
		(fp_line
			(start -0.7874 0.4064)
			(end -0.7874 -0.4064)
			(stroke
				(width 0.1524)
				(type default)
			)
			(layer "F.SilkS")
		)
		(fp_line
			(start 0.7874 0.4064)
			(end -0.7874 0.4064)
			(stroke
				(width 0.1524)
				(type default)
			)
			(layer "F.SilkS")
		)
		(fp_line
			(start -0.7874 -0.4064)
			(end 0.7874 -0.4064)
			(stroke
				(width 0.1524)
				(type default)
			)
			(layer "F.SilkS")
		)
		(fp_line
			(start 0.7874 -0.4064)
			(end 0.7874 0.4064)
			(stroke
				(width 0.1524)
				(type default)
			)
			(layer "F.SilkS")
		)
		(fp_line
			(start -0.67945 0.3048)
			(end -0.67945 -0.305054)
			(stroke
				(width 0.1)
				(type default)
			)
			(layer "F.Fab")
		)
		(fp_line
			(start -0.12065 0.3048)
			(end -0.67945 0.3048)
			(stroke
				(width 0.1)
				(type default)
			)
			(layer "F.Fab")
		)
		(fp_line
			(start 0.120396 0.3048)
			(end 0.120396 0.2794)
			(stroke
				(width 0.1)
				(type default)
			)
			(layer "F.Fab")
		)
		(fp_line
			(start 0.67945 0.3048)
			(end 0.120396 0.3048)
			(stroke
				(width 0.1)
				(type default)
			)
			(layer "F.Fab")
		)
		(fp_line
			(start -0.12065 0.2794)
			(end -0.12065 0.3048)
			(stroke
				(width 0.1)
				(type default)
			)
			(layer "F.Fab")
		)
		(fp_line
			(start 0.120396 0.2794)
			(end -0.12065 0.2794)
			(stroke
				(width 0.1)
				(type default)
			)
			(layer "F.Fab")
		)
		(fp_line
			(start -0.12065 -0.2794)
			(end 0.12065 -0.2794)
			(stroke
				(width 0.1)
				(type default)
			)
			(layer "F.Fab")
		)
		(fp_line
			(start 0.12065 -0.2794)
			(end 0.12065 -0.3048)
			(stroke
				(width 0.1)
				(type default)
			)
			(layer "F.Fab")
		)
		(fp_line
			(start 0.12065 -0.3048)
			(end 0.67945 -0.3048)
			(stroke
				(width 0.1)
				(type default)
			)
			(layer "F.Fab")
		)
		(fp_line
			(start 0.67945 -0.3048)
			(end 0.67945 0.3048)
			(stroke
				(width 0.1)
				(type default)
			)
			(layer "F.Fab")
		)
		(fp_line
			(start -0.67945 -0.305054)
			(end -0.12065 -0.305054)
			(stroke
				(width 0.1)
				(type default)
			)
			(layer "F.Fab")
		)
		(fp_line
			(start -0.12065 -0.305054)
			(end -0.12065 -0.2794)
			(stroke
				(width 0.1)
				(type default)
			)
			(layer "F.Fab")
		)
		(pad "1" smd circle
			(at -0.40005 0 270)
			(size 0 0)
			(layers "F.Cu" "F.Mask" "F.Paste")
			(net "SW_PVCCFA_EHV_FIVRA_CPU0_BOOT1_")
		)
		(pad "2" smd circle
			(at 0.40005 0 270)
			(size 0 0)
			(layers "F.Cu" "F.Mask" "F.Paste")
			(net "SW_PVCCFA_EHV_FIVRA_CPU0_BOOTR1")
		)
	)
	(footprint ""
		(layer "F.Cu")
		(at 367.7412 -74.3458 90)
		(property "Reference" "R4702"
			(at 0 0 90)
			(layer "F.SilkS")
			(hide yes)
			(effects
				(font
					(size 1.27 1.27)
				)
			)
		)
		(property "Value" ""
			(at 0 0 90)
			(layer "F.Fab")
			(effects
				(font
					(size 1.27 1.27)
				)
			)
		)
		(duplicate_pad_numbers_are_jumpers no)
		(fp_line
			(start 0.7874 -0.4064)
			(end 0.7874 0.4064)
			(stroke
				(width 0.1524)
				(type default)
			)
			(layer "F.SilkS")
		)
		(fp_line
			(start -0.7874 -0.4064)
			(end 0.7874 -0.4064)
			(stroke
				(width 0.1524)
				(type default)
			)
			(layer "F.SilkS")
		)
		(fp_line
			(start 0.7874 0.4064)
			(end -0.7874 0.4064)
			(stroke
				(width 0.1524)
				(type default)
			)
			(layer "F.SilkS")
		)
		(fp_line
			(start -0.7874 0.4064)
			(end -0.7874 -0.4064)
			(stroke
				(width 0.1524)
				(type default)
			)
			(layer "F.SilkS")
		)
		(fp_line
			(start -0.12065 -0.305054)
			(end -0.12065 -0.2794)
			(stroke
				(width 0.1)
				(type default)
			)
			(layer "F.Fab")
		)
		(fp_line
			(start -0.67945 -0.305054)
			(end -0.12065 -0.305054)
			(stroke
				(width 0.1)
				(type default)
			)
			(layer "F.Fab")
		)
		(fp_line
			(start 0.67945 -0.3048)
			(end 0.67945 0.3048)
			(stroke
				(width 0.1)
				(type default)
			)
			(layer "F.Fab")
		)
		(fp_line
			(start 0.12065 -0.3048)
			(end 0.67945 -0.3048)
			(stroke
				(width 0.1)
				(type default)
			)
			(layer "F.Fab")
		)
		(fp_line
			(start 0.12065 -0.2794)
			(end 0.12065 -0.3048)
			(stroke
				(width 0.1)
				(type default)
			)
			(layer "F.Fab")
		)
		(fp_line
			(start -0.12065 -0.2794)
			(end 0.12065 -0.2794)
			(stroke
				(width 0.1)
				(type default)
			)
			(layer "F.Fab")
		)
		(fp_line
			(start 0.120396 0.2794)
			(end -0.12065 0.2794)
			(stroke
				(width 0.1)
				(type default)
			)
			(layer "F.Fab")
		)
		(fp_line
			(start -0.12065 0.2794)
			(end -0.12065 0.3048)
			(stroke
				(width 0.1)
				(type default)
			)
			(layer "F.Fab")
		)
		(fp_line
			(start 0.67945 0.3048)
			(end 0.120396 0.3048)
			(stroke
				(width 0.1)
				(type default)
			)
			(layer "F.Fab")
		)
		(fp_line
			(start 0.120396 0.3048)
			(end 0.120396 0.2794)
			(stroke
				(width 0.1)
				(type default)
			)
			(layer "F.Fab")
		)
		(fp_line
			(start -0.12065 0.3048)
			(end -0.67945 0.3048)
			(stroke
				(width 0.1)
				(type default)
			)
			(layer "F.Fab")
		)
		(fp_line
			(start -0.67945 0.3048)
			(end -0.67945 -0.305054)
			(stroke
				(width 0.1)
				(type default)
			)
			(layer "F.Fab")
		)
		(pad "1" smd circle
			(at -0.40005 0 90)
			(size 0 0)
			(layers "F.Cu" "F.Mask" "F.Paste")
			(net "LED_P12V_AUX_R1")
		)
		(pad "2" smd circle
			(at 0.40005 0 90)
			(size 0 0)
			(layers "F.Cu" "F.Mask" "F.Paste")
			(net "LED_P12V_AUX_R2")
		)
	)
	(footprint ""
		(layer "F.Cu")
		(at 88.451182 -180.33873)
		(property "Reference" "R4261"
			(at 0 0 0)
			(layer "F.SilkS")
			(hide yes)
			(effects
				(font
					(size 1.27 1.27)
				)
			)
		)
		(property "Value" ""
			(at 0 0 0)
			(layer "F.Fab")
			(effects
				(font
					(size 1.27 1.27)
				)
			)
		)
		(duplicate_pad_numbers_are_jumpers no)
		(fp_line
			(start -0.7874 -0.4064)
			(end 0.7874 -0.4064)
			(stroke
				(width 0.1524)
				(type default)
			)
			(layer "F.SilkS")
		)
		(fp_line
			(start -0.7874 0.4064)
			(end -0.7874 -0.4064)
			(stroke
				(width 0.1524)
				(type default)
			)
			(layer "F.SilkS")
		)
		(fp_line
			(start 0.7874 -0.4064)
			(end 0.7874 0.4064)
			(stroke
				(width 0.1524)
				(type default)
			)
			(layer "F.SilkS")
		)
		(fp_line
			(start 0.7874 0.4064)
			(end -0.7874 0.4064)
			(stroke
				(width 0.1524)
				(type default)
			)
			(layer "F.SilkS")
		)
		(fp_line
			(start -0.67945 -0.305054)
			(end -0.12065 -0.305054)
			(stroke
				(width 0.1)
				(type default)
			)
			(layer "F.Fab")
		)
		(fp_line
			(start -0.67945 0.3048)
			(end -0.67945 -0.305054)
			(stroke
				(width 0.1)
				(type default)
			)
			(layer "F.Fab")
		)
		(fp_line
			(start -0.12065 -0.305054)
			(end -0.12065 -0.2794)
			(stroke
				(width 0.1)
				(type default)
			)
			(layer "F.Fab")
		)
		(fp_line
			(start -0.12065 -0.2794)
			(end 0.12065 -0.2794)
			(stroke
				(width 0.1)
				(type default)
			)
			(layer "F.Fab")
		)
		(fp_line
			(start -0.12065 0.2794)
			(end -0.12065 0.3048)
			(stroke
				(width 0.1)
				(type default)
			)
			(layer "F.Fab")
		)
		(fp_line
			(start -0.12065 0.3048)
			(end -0.67945 0.3048)
			(stroke
				(width 0.1)
				(type default)
			)
			(layer "F.Fab")
		)
		(fp_line
			(start 0.120396 0.2794)
			(end -0.12065 0.2794)
			(stroke
				(width 0.1)
				(type default)
			)
			(layer "F.Fab")
		)
		(fp_line
			(start 0.120396 0.3048)
			(end 0.120396 0.2794)
			(stroke
				(width 0.1)
				(type default)
			)
			(layer "F.Fab")
		)
		(fp_line
			(start 0.12065 -0.3048)
			(end 0.67945 -0.3048)
			(stroke
				(width 0.1)
				(type default)
			)
			(layer "F.Fab")
		)
		(fp_line
			(start 0.12065 -0.2794)
			(end 0.12065 -0.3048)
			(stroke
				(width 0.1)
				(type default)
			)
			(layer "F.Fab")
		)
		(fp_line
			(start 0.67945 -0.3048)
			(end 0.67945 0.3048)
			(stroke
				(width 0.1)
				(type default)
			)
			(layer "F.Fab")
		)
		(fp_line
			(start 0.67945 0.3048)
			(end 0.120396 0.3048)
			(stroke
				(width 0.1)
				(type default)
			)
			(layer "F.Fab")
		)
		(pad "1" smd circle
			(at -0.40005 0)
			(size 0 0)
			(layers "F.Cu" "F.Mask" "F.Paste")
			(net "PD_CPU1_BIST_ENABLE")
		)
		(pad "2" smd circle
			(at 0.40005 0)
			(size 0 0)
			(layers "F.Cu" "F.Mask" "F.Paste")
			(net "GND")
		)
	)
)
